(kicad_pcb
	(version 20260206)
	(generator "pcbnew")
	(generator_version "10.0")
	(general
		(thickness 1.6)
		(legacy_teardrops no)
	)
	(paper "A4")
	(title_block
		(title "01162023_DA0F0TEBIF0_F0T_Expander_BD_F_brd_V02_OCP.brd")
		(comment 1 "Grand Teton / footprints 7622-7628 of 9728")
	)
	(layers
		(0 "F.Cu" signal "TOP")
		(4 "In1.Cu" signal "GND")
		(6 "In2.Cu" signal "VCC")
		(8 "In3.Cu" signal "VCC1")
		(10 "In4.Cu" signal "GND1")
		(12 "In5.Cu" signal "IN1")
		(14 "In6.Cu" signal "GND2")
		(16 "In7.Cu" signal "IN2")
		(18 "In8.Cu" signal "GND3")
		(20 "In9.Cu" signal "IN3")
		(22 "In10.Cu" signal "GND4")
		(24 "In11.Cu" signal "IN4")
		(26 "In12.Cu" signal "GND5")
		(28 "In13.Cu" signal "IN5")
		(30 "In14.Cu" signal "GND6")
		(32 "In15.Cu" signal "IN6")
		(34 "In16.Cu" signal "GND7")
		(2 "B.Cu" signal "BOTTOM")
		(9 "F.Adhes" user "F.Adhesive")
		(11 "B.Adhes" user "B.Adhesive")
		(13 "F.Paste" user "Package Geometry/Pastemask Top")
		(15 "B.Paste" user "Package Geometry/Pastemask Bottom")
		(5 "F.SilkS" user "Ref Des/Silkscreen Top")
		(7 "B.SilkS" user "Ref Des/Silkscreen Bottom")
		(1 "F.Mask" user "Board Geometry/Soldermask Top")
		(3 "B.Mask" user "Board Geometry/Soldermask Bottom")
		(17 "Dwgs.User" user "User.Drawings")
		(19 "Cmts.User" user "User.Comments")
		(21 "Eco1.User" user "User.Eco1")
		(23 "Eco2.User" user "User.Eco2")
		(25 "Edge.Cuts" user "Board Geometry/Outline")
		(27 "Margin" user)
		(31 "F.CrtYd" user "Package Geometry/Place Bound Top")
		(29 "B.CrtYd" user "Package Geometry/Place Bound Bottom")
		(35 "F.Fab" user "Ref Des/Assembly Top")
		(33 "B.Fab" user "Ref Des/Assembly Bottom")
	)
	(footprint ""
		(layer "B.Cu")
		(at 107.700064 -83.72856 -90)
		(property "Reference" "C2663"
			(at 0 0 90)
			(layer "B.SilkS")
			(hide yes)
			(effects
				(font
					(size 1.27 1.27)
				)
				(justify mirror)
			)
		)
		(property "Value" ""
			(at 0 0 90)
			(layer "B.Fab")
			(effects
				(font
					(size 1.27 1.27)
				)
				(justify mirror)
			)
		)
		(duplicate_pad_numbers_are_jumpers no)
		(fp_line
			(start -0.7874 0.4064)
			(end 0.7874 0.4064)
			(stroke
				(width 0.1524)
				(type default)
			)
			(layer "B.SilkS")
		)
		(fp_line
			(start 0.7874 0.4064)
			(end 0.7874 -0.4064)
			(stroke
				(width 0.1524)
				(type default)
			)
			(layer "B.SilkS")
		)
		(fp_line
			(start -0.7874 -0.4064)
			(end -0.7874 0.4064)
			(stroke
				(width 0.1524)
				(type default)
			)
			(layer "B.SilkS")
		)
		(fp_line
			(start 0.7874 -0.4064)
			(end -0.7874 -0.4064)
			(stroke
				(width 0.1524)
				(type default)
			)
			(layer "B.SilkS")
		)
		(fp_line
			(start -0.67945 0.3048)
			(end -0.120396 0.3048)
			(stroke
				(width 0.1)
				(type default)
			)
			(layer "B.Fab")
		)
		(fp_line
			(start -0.120396 0.3048)
			(end -0.120396 0.2794)
			(stroke
				(width 0.1)
				(type default)
			)
			(layer "B.Fab")
		)
		(fp_line
			(start 0.12065 0.3048)
			(end 0.67945 0.3048)
			(stroke
				(width 0.1)
				(type default)
			)
			(layer "B.Fab")
		)
		(fp_line
			(start 0.67945 0.3048)
			(end 0.67945 -0.305054)
			(stroke
				(width 0.1)
				(type default)
			)
			(layer "B.Fab")
		)
		(fp_line
			(start -0.120396 0.2794)
			(end 0.12065 0.2794)
			(stroke
				(width 0.1)
				(type default)
			)
			(layer "B.Fab")
		)
		(fp_line
			(start 0.12065 0.2794)
			(end 0.12065 0.3048)
			(stroke
				(width 0.1)
				(type default)
			)
			(layer "B.Fab")
		)
		(fp_line
			(start -0.12065 -0.2794)
			(end -0.12065 -0.3048)
			(stroke
				(width 0.1)
				(type default)
			)
			(layer "B.Fab")
		)
		(fp_line
			(start 0.12065 -0.2794)
			(end -0.12065 -0.2794)
			(stroke
				(width 0.1)
				(type default)
			)
			(layer "B.Fab")
		)
		(fp_line
			(start -0.67945 -0.3048)
			(end -0.67945 0.3048)
			(stroke
				(width 0.1)
				(type default)
			)
			(layer "B.Fab")
		)
		(fp_line
			(start -0.12065 -0.3048)
			(end -0.67945 -0.3048)
			(stroke
				(width 0.1)
				(type default)
			)
			(layer "B.Fab")
		)
		(fp_line
			(start 0.12065 -0.305054)
			(end 0.12065 -0.2794)
			(stroke
				(width 0.1)
				(type default)
			)
			(layer "B.Fab")
		)
		(fp_line
			(start 0.67945 -0.305054)
			(end 0.12065 -0.305054)
			(stroke
				(width 0.1)
				(type default)
			)
			(layer "B.Fab")
		)
		(pad "1" smd circle
			(at 0.40005 0 90)
			(size 0 0)
			(layers "B.Cu" "B.Mask" "B.Paste")
			(net "P3V3_VDD_9ZXL0851_0_7")
		)
		(pad "2" smd circle
			(at -0.40005 0 90)
			(size 0 0)
			(layers "B.Cu" "B.Mask" "B.Paste")
			(net "GND")
		)
	)
	(footprint ""
		(layer "B.Cu")
		(at 130.539744 -205.225142 180)
		(property "Reference" "R922"
			(at 0 0 0)
			(layer "B.SilkS")
			(hide yes)
			(effects
				(font
					(size 1.27 1.27)
				)
				(justify mirror)
			)
		)
		(property "Value" ""
			(at 0 0 0)
			(layer "B.Fab")
			(effects
				(font
					(size 1.27 1.27)
				)
				(justify mirror)
			)
		)
		(duplicate_pad_numbers_are_jumpers no)
		(fp_line
			(start 0.7874 0.4064)
			(end 0.7874 -0.4064)
			(stroke
				(width 0.1524)
				(type default)
			)
			(layer "B.SilkS")
		)
		(fp_line
			(start 0.7874 -0.4064)
			(end -0.7874 -0.4064)
			(stroke
				(width 0.1524)
				(type default)
			)
			(layer "B.SilkS")
		)
		(fp_line
			(start -0.7874 0.4064)
			(end 0.7874 0.4064)
			(stroke
				(width 0.1524)
				(type default)
			)
			(layer "B.SilkS")
		)
		(fp_line
			(start -0.7874 -0.4064)
			(end -0.7874 0.4064)
			(stroke
				(width 0.1524)
				(type default)
			)
			(layer "B.SilkS")
		)
		(fp_line
			(start 0.67945 0.3048)
			(end 0.67945 -0.305054)
			(stroke
				(width 0.1)
				(type default)
			)
			(layer "B.Fab")
		)
		(fp_line
			(start 0.67945 -0.305054)
			(end 0.12065 -0.305054)
			(stroke
				(width 0.1)
				(type default)
			)
			(layer "B.Fab")
		)
		(fp_line
			(start 0.12065 0.3048)
			(end 0.67945 0.3048)
			(stroke
				(width 0.1)
				(type default)
			)
			(layer "B.Fab")
		)
		(fp_line
			(start 0.12065 0.2794)
			(end 0.12065 0.3048)
			(stroke
				(width 0.1)
				(type default)
			)
			(layer "B.Fab")
		)
		(fp_line
			(start 0.12065 -0.2794)
			(end -0.12065 -0.2794)
			(stroke
				(width 0.1)
				(type default)
			)
			(layer "B.Fab")
		)
		(fp_line
			(start 0.12065 -0.305054)
			(end 0.12065 -0.2794)
			(stroke
				(width 0.1)
				(type default)
			)
			(layer "B.Fab")
		)
		(fp_line
			(start -0.120396 0.3048)
			(end -0.120396 0.2794)
			(stroke
				(width 0.1)
				(type default)
			)
			(layer "B.Fab")
		)
		(fp_line
			(start -0.120396 0.2794)
			(end 0.12065 0.2794)
			(stroke
				(width 0.1)
				(type default)
			)
			(layer "B.Fab")
		)
		(fp_line
			(start -0.12065 -0.2794)
			(end -0.12065 -0.3048)
			(stroke
				(width 0.1)
				(type default)
			)
			(layer "B.Fab")
		)
		(fp_line
			(start -0.12065 -0.3048)
			(end -0.67945 -0.3048)
			(stroke
				(width 0.1)
				(type default)
			)
			(layer "B.Fab")
		)
		(fp_line
			(start -0.67945 0.3048)
			(end -0.120396 0.3048)
			(stroke
				(width 0.1)
				(type default)
			)
			(layer "B.Fab")
		)
		(fp_line
			(start -0.67945 -0.3048)
			(end -0.67945 0.3048)
			(stroke
				(width 0.1)
				(type default)
			)
			(layer "B.Fab")
		)
		(pad "1" smd circle
			(at 0.40005 0)
			(size 0 0)
			(layers "B.Cu" "B.Mask" "B.Paste")
			(net "FT4232_CLI_EEPROM_R_SCL")
		)
		(pad "2" smd circle
			(at -0.40005 0)
			(size 0 0)
			(layers "B.Cu" "B.Mask" "B.Paste")
			(net "FT4232_CLI_EEPROM_SCL")
		)
	)
	(footprint ""
		(layer "B.Cu")
		(at 280.241502 -303.024794)
		(property "Reference" "C3343"
			(at 0 0 0)
			(layer "B.SilkS")
			(hide yes)
			(effects
				(font
					(size 1.27 1.27)
				)
				(justify mirror)
			)
		)
		(property "Value" ""
			(at 0 0 0)
			(layer "B.Fab")
			(effects
				(font
					(size 1.27 1.27)
				)
				(justify mirror)
			)
		)
		(duplicate_pad_numbers_are_jumpers no)
		(fp_line
			(start -0.299974 -0.150114)
			(end -0.299974 0.150114)
			(stroke
				(width 0.1)
				(type default)
			)
			(layer "B.Fab")
		)
		(fp_line
			(start -0.299974 0.150114)
			(end 0.299974 0.150114)
			(stroke
				(width 0.1)
				(type default)
			)
			(layer "B.Fab")
		)
		(fp_line
			(start 0.299974 -0.150114)
			(end -0.299974 -0.150114)
			(stroke
				(width 0.1)
				(type default)
			)
			(layer "B.Fab")
		)
		(fp_line
			(start 0.299974 0.150114)
			(end 0.299974 -0.150114)
			(stroke
				(width 0.1)
				(type default)
			)
			(layer "B.Fab")
		)
		(pad "1" smd rect
			(at 0.2667 0 180)
			(size 0.3048 0.381)
			(layers "B.Cu" "B.Mask" "B.Paste")
			(net "P1V8_VDDA_PEX2")
		)
		(pad "2" smd rect
			(at -0.2667 0 180)
			(size 0.3048 0.381)
			(layers "B.Cu" "B.Mask" "B.Paste")
			(net "GND")
		)
	)
	(footprint ""
		(layer "B.Cu")
		(at 210.458812 -223.61906)
		(property "Reference" "R6800"
			(at 0 0 0)
			(layer "B.SilkS")
			(hide yes)
			(effects
				(font
					(size 1.27 1.27)
				)
				(justify mirror)
			)
		)
		(property "Value" ""
			(at 0 0 0)
			(layer "B.Fab")
			(effects
				(font
					(size 1.27 1.27)
				)
				(justify mirror)
			)
		)
		(duplicate_pad_numbers_are_jumpers no)
		(fp_line
			(start -0.7874 -0.4064)
			(end -0.7874 0.4064)
			(stroke
				(width 0.1524)
				(type default)
			)
			(layer "B.SilkS")
		)
		(fp_line
			(start -0.7874 0.4064)
			(end 0.7874 0.4064)
			(stroke
				(width 0.1524)
				(type default)
			)
			(layer "B.SilkS")
		)
		(fp_line
			(start 0.7874 -0.4064)
			(end -0.7874 -0.4064)
			(stroke
				(width 0.1524)
				(type default)
			)
			(layer "B.SilkS")
		)
		(fp_line
			(start 0.7874 0.4064)
			(end 0.7874 -0.4064)
			(stroke
				(width 0.1524)
				(type default)
			)
			(layer "B.SilkS")
		)
		(fp_line
			(start -0.67945 -0.3048)
			(end -0.67945 0.3048)
			(stroke
				(width 0.1)
				(type default)
			)
			(layer "B.Fab")
		)
		(fp_line
			(start -0.67945 0.3048)
			(end -0.120396 0.3048)
			(stroke
				(width 0.1)
				(type default)
			)
			(layer "B.Fab")
		)
		(fp_line
			(start -0.12065 -0.3048)
			(end -0.67945 -0.3048)
			(stroke
				(width 0.1)
				(type default)
			)
			(layer "B.Fab")
		)
		(fp_line
			(start -0.12065 -0.2794)
			(end -0.12065 -0.3048)
			(stroke
				(width 0.1)
				(type default)
			)
			(layer "B.Fab")
		)
		(fp_line
			(start -0.120396 0.2794)
			(end 0.12065 0.2794)
			(stroke
				(width 0.1)
				(type default)
			)
			(layer "B.Fab")
		)
		(fp_line
			(start -0.120396 0.3048)
			(end -0.120396 0.2794)
			(stroke
				(width 0.1)
				(type default)
			)
			(layer "B.Fab")
		)
		(fp_line
			(start 0.12065 -0.305054)
			(end 0.12065 -0.2794)
			(stroke
				(width 0.1)
				(type default)
			)
			(layer "B.Fab")
		)
		(fp_line
			(start 0.12065 -0.2794)
			(end -0.12065 -0.2794)
			(stroke
				(width 0.1)
				(type default)
			)
			(layer "B.Fab")
		)
		(fp_line
			(start 0.12065 0.2794)
			(end 0.12065 0.3048)
			(stroke
				(width 0.1)
				(type default)
			)
			(layer "B.Fab")
		)
		(fp_line
			(start 0.12065 0.3048)
			(end 0.67945 0.3048)
			(stroke
				(width 0.1)
				(type default)
			)
			(layer "B.Fab")
		)
		(fp_line
			(start 0.67945 -0.305054)
			(end 0.12065 -0.305054)
			(stroke
				(width 0.1)
				(type default)
			)
			(layer "B.Fab")
		)
		(fp_line
			(start 0.67945 0.3048)
			(end 0.67945 -0.305054)
			(stroke
				(width 0.1)
				(type default)
			)
			(layer "B.Fab")
		)
		(pad "1" smd circle
			(at 0.40005 0 180)
			(size 0 0)
			(layers "B.Cu" "B.Mask" "B.Paste")
			(net "SMB_BIC_FPGA_SDA")
		)
		(pad "2" smd circle
			(at -0.40005 0 180)
			(size 0 0)
			(layers "B.Cu" "B.Mask" "B.Paste")
			(net "SMB_BIC_FPGA_R1_SDA")
		)
	)
	(footprint ""
		(layer "B.Cu")
		(at 349.272098 -283.818584 90)
		(property "Reference" "PR152"
			(at 0 0 90)
			(layer "B.SilkS")
			(hide yes)
			(effects
				(font
					(size 1.27 1.27)
				)
				(justify mirror)
			)
		)
		(property "Value" ""
			(at 0 0 90)
			(layer "B.Fab")
			(effects
				(font
					(size 1.27 1.27)
				)
				(justify mirror)
			)
		)
		(duplicate_pad_numbers_are_jumpers no)
		(fp_line
			(start 0.7874 -0.4064)
			(end -0.7874 -0.4064)
			(stroke
				(width 0.1524)
				(type default)
			)
			(layer "B.SilkS")
		)
		(fp_line
			(start -0.7874 -0.4064)
			(end -0.7874 0.4064)
			(stroke
				(width 0.1524)
				(type default)
			)
			(layer "B.SilkS")
		)
		(fp_line
			(start 0.7874 0.4064)
			(end 0.7874 -0.4064)
			(stroke
				(width 0.1524)
				(type default)
			)
			(layer "B.SilkS")
		)
		(fp_line
			(start -0.7874 0.4064)
			(end 0.7874 0.4064)
			(stroke
				(width 0.1524)
				(type default)
			)
			(layer "B.SilkS")
		)
		(fp_line
			(start 0.67945 -0.305054)
			(end 0.12065 -0.305054)
			(stroke
				(width 0.1)
				(type default)
			)
			(layer "B.Fab")
		)
		(fp_line
			(start 0.12065 -0.305054)
			(end 0.12065 -0.2794)
			(stroke
				(width 0.1)
				(type default)
			)
			(layer "B.Fab")
		)
		(fp_line
			(start -0.12065 -0.3048)
			(end -0.67945 -0.3048)
			(stroke
				(width 0.1)
				(type default)
			)
			(layer "B.Fab")
		)
		(fp_line
			(start -0.67945 -0.3048)
			(end -0.67945 0.3048)
			(stroke
				(width 0.1)
				(type default)
			)
			(layer "B.Fab")
		)
		(fp_line
			(start 0.12065 -0.2794)
			(end -0.12065 -0.2794)
			(stroke
				(width 0.1)
				(type default)
			)
			(layer "B.Fab")
		)
		(fp_line
			(start -0.12065 -0.2794)
			(end -0.12065 -0.3048)
			(stroke
				(width 0.1)
				(type default)
			)
			(layer "B.Fab")
		)
		(fp_line
			(start 0.12065 0.2794)
			(end 0.12065 0.3048)
			(stroke
				(width 0.1)
				(type default)
			)
			(layer "B.Fab")
		)
		(fp_line
			(start -0.120396 0.2794)
			(end 0.12065 0.2794)
			(stroke
				(width 0.1)
				(type default)
			)
			(layer "B.Fab")
		)
		(fp_line
			(start 0.67945 0.3048)
			(end 0.67945 -0.305054)
			(stroke
				(width 0.1)
				(type default)
			)
			(layer "B.Fab")
		)
		(fp_line
			(start 0.12065 0.3048)
			(end 0.67945 0.3048)
			(stroke
				(width 0.1)
				(type default)
			)
			(layer "B.Fab")
		)
		(fp_line
			(start -0.120396 0.3048)
			(end -0.120396 0.2794)
			(stroke
				(width 0.1)
				(type default)
			)
			(layer "B.Fab")
		)
		(fp_line
			(start -0.67945 0.3048)
			(end -0.120396 0.3048)
			(stroke
				(width 0.1)
				(type default)
			)
			(layer "B.Fab")
		)
		(pad "1" smd circle
			(at 0.40005 0 270)
			(size 0 0)
			(layers "B.Cu" "B.Mask" "B.Paste")
			(net "P0V8_PEX2_PVCC")
		)
		(pad "2" smd circle
			(at -0.40005 0 270)
			(size 0 0)
			(layers "B.Cu" "B.Mask" "B.Paste")
			(net "P0V8_PEX2_VCC2")
		)
	)
	(footprint ""
		(layer "B.Cu")
		(at 170.524932 -305.399948 -90)
		(property "Reference" "C3156"
			(at 0 0 90)
			(layer "B.SilkS")
			(hide yes)
			(effects
				(font
					(size 1.27 1.27)
				)
				(justify mirror)
			)
		)
		(property "Value" ""
			(at 0 0 90)
			(layer "B.Fab")
			(effects
				(font
					(size 1.27 1.27)
				)
				(justify mirror)
			)
		)
		(duplicate_pad_numbers_are_jumpers no)
		(fp_line
			(start -0.299974 0.150114)
			(end 0.299974 0.150114)
			(stroke
				(width 0.1)
				(type default)
			)
			(layer "B.Fab")
		)
		(fp_line
			(start 0.299974 0.150114)
			(end 0.299974 -0.150114)
			(stroke
				(width 0.1)
				(type default)
			)
			(layer "B.Fab")
		)
		(fp_line
			(start -0.299974 -0.150114)
			(end -0.299974 0.150114)
			(stroke
				(width 0.1)
				(type default)
			)
			(layer "B.Fab")
		)
		(fp_line
			(start 0.299974 -0.150114)
			(end -0.299974 -0.150114)
			(stroke
				(width 0.1)
				(type default)
			)
			(layer "B.Fab")
		)
		(pad "1" smd rect
			(at 0.2667 0 90)
			(size 0.3048 0.381)
			(layers "B.Cu" "B.Mask" "B.Paste")
			(net "P1V25_SERDES_VDDPLL_PEX1")
		)
		(pad "2" smd rect
			(at -0.2667 0 90)
			(size 0.3048 0.381)
			(layers "B.Cu" "B.Mask" "B.Paste")
			(net "GND")
		)
	)
	(footprint ""
		(layer "B.Cu")
		(at 124.331222 -201.93635 180)
		(property "Reference" "R918"
			(at 0 0 0)
			(layer "B.SilkS")
			(hide yes)
			(effects
				(font
					(size 1.27 1.27)
				)
				(justify mirror)
			)
		)
		(property "Value" ""
			(at 0 0 0)
			(layer "B.Fab")
			(effects
				(font
					(size 1.27 1.27)
				)
				(justify mirror)
			)
		)
		(duplicate_pad_numbers_are_jumpers no)
		(fp_line
			(start 0.7874 0.4064)
			(end 0.7874 -0.4064)
			(stroke
				(width 0.1524)
				(type default)
			)
			(layer "B.SilkS")
		)
		(fp_line
			(start 0.7874 -0.4064)
			(end -0.7874 -0.4064)
			(stroke
				(width 0.1524)
				(type default)
			)
			(layer "B.SilkS")
		)
		(fp_line
			(start -0.7874 0.4064)
			(end 0.7874 0.4064)
			(stroke
				(width 0.1524)
				(type default)
			)
			(layer "B.SilkS")
		)
		(fp_line
			(start -0.7874 -0.4064)
			(end -0.7874 0.4064)
			(stroke
				(width 0.1524)
				(type default)
			)
			(layer "B.SilkS")
		)
		(fp_line
			(start 0.67945 0.3048)
			(end 0.67945 -0.305054)
			(stroke
				(width 0.1)
				(type default)
			)
			(layer "B.Fab")
		)
		(fp_line
			(start 0.67945 -0.305054)
			(end 0.12065 -0.305054)
			(stroke
				(width 0.1)
				(type default)
			)
			(layer "B.Fab")
		)
		(fp_line
			(start 0.12065 0.3048)
			(end 0.67945 0.3048)
			(stroke
				(width 0.1)
				(type default)
			)
			(layer "B.Fab")
		)
		(fp_line
			(start 0.12065 0.2794)
			(end 0.12065 0.3048)
			(stroke
				(width 0.1)
				(type default)
			)
			(layer "B.Fab")
		)
		(fp_line
			(start 0.12065 -0.2794)
			(end -0.12065 -0.2794)
			(stroke
				(width 0.1)
				(type default)
			)
			(layer "B.Fab")
		)
		(fp_line
			(start 0.12065 -0.305054)
			(end 0.12065 -0.2794)
			(stroke
				(width 0.1)
				(type default)
			)
			(layer "B.Fab")
		)
		(fp_line
			(start -0.120396 0.3048)
			(end -0.120396 0.2794)
			(stroke
				(width 0.1)
				(type default)
			)
			(layer "B.Fab")
		)
		(fp_line
			(start -0.120396 0.2794)
			(end 0.12065 0.2794)
			(stroke
				(width 0.1)
				(type default)
			)
			(layer "B.Fab")
		)
		(fp_line
			(start -0.12065 -0.2794)
			(end -0.12065 -0.3048)
			(stroke
				(width 0.1)
				(type default)
			)
			(layer "B.Fab")
		)
		(fp_line
			(start -0.12065 -0.3048)
			(end -0.67945 -0.3048)
			(stroke
				(width 0.1)
				(type default)
			)
			(layer "B.Fab")
		)
		(fp_line
			(start -0.67945 0.3048)
			(end -0.120396 0.3048)
			(stroke
				(width 0.1)
				(type default)
			)
			(layer "B.Fab")
		)
		(fp_line
			(start -0.67945 -0.3048)
			(end -0.67945 0.3048)
			(stroke
				(width 0.1)
				(type default)
			)
			(layer "B.Fab")
		)
		(pad "1" smd circle
			(at 0.40005 0)
			(size 0 0)
			(layers "B.Cu" "B.Mask" "B.Paste")
			(net "FT4232_CLI_EEPROM_DO")
		)
		(pad "2" smd circle
			(at -0.40005 0)
			(size 0 0)
			(layers "B.Cu" "B.Mask" "B.Paste")
			(net "P3V3_AUX")
		)
	)
)
